(kicad_pcb
	(version 20260206)
	(generator "pcbnew")
	(generator_version "10.0")
	(general
		(thickness 1.6)
		(legacy_teardrops no)
	)
	(paper "A4")
	(title_block
		(title "04192023_DAF0TMB3IC0_F0TG_MB_C_brd_V02_OCP.brd")
		(comment 1 "Grand Teton / footprint 2783 of 8354 (U26), pads 1878-1989 of 6102")
	)
	(layers
		(0 "F.Cu" signal "TOP")
		(4 "In1.Cu" signal "GND")
		(6 "In2.Cu" signal "IN1")
		(8 "In3.Cu" signal "GND1")
		(10 "In4.Cu" signal "IN2")
		(12 "In5.Cu" signal "GND2")
		(14 "In6.Cu" signal "IN3")
		(16 "In7.Cu" signal "GND3")
		(18 "In8.Cu" signal "VCC")
		(20 "In9.Cu" signal "VCC1")
		(22 "In10.Cu" signal "GND4")
		(24 "In11.Cu" signal "IN4")
		(26 "In12.Cu" signal "GND5")
		(28 "In13.Cu" signal "IN5")
		(30 "In14.Cu" signal "GND6")
		(32 "In15.Cu" signal "IN6")
		(34 "In16.Cu" signal "GND7")
		(2 "B.Cu" signal "BOTTOM")
		(9 "F.Adhes" user "F.Adhesive")
		(11 "B.Adhes" user "B.Adhesive")
		(13 "F.Paste" user "Package Geometry/Pastemask Top")
		(15 "B.Paste" user "Package Geometry/Pastemask Bottom")
		(5 "F.SilkS" user "Ref Des/Silkscreen Top")
		(7 "B.SilkS" user "Ref Des/Silkscreen Bottom")
		(1 "F.Mask" user "Board Geometry/Soldermask Top")
		(3 "B.Mask" user "Board Geometry/Soldermask Bottom")
		(17 "Dwgs.User" user "User.Drawings")
		(19 "Cmts.User" user "User.Comments")
		(21 "Eco1.User" user "User.Eco1")
		(23 "Eco2.User" user "User.Eco2")
		(25 "Edge.Cuts" user "Board Geometry/Outline")
		(27 "Margin" user)
		(31 "F.CrtYd" user "Package Geometry/Place Bound Top")
		(29 "B.CrtYd" user "Package Geometry/Place Bound Bottom")
		(35 "F.Fab" user "Ref Des/Assembly Top")
		(33 "B.Fab" user "Ref Des/Assembly Bottom")
	)
	(footprint ""
		(layer "F.Cu")
		(at 111.927894 -258.880356 180)
		(property "Reference" "U26"
			(at -45.05579 -61.794136 0)
			(unlocked yes)
			(layer "F.SilkS")
			(effects
				(font
					(size 0.7874 0.5842)
					(thickness 0.1524)
				)
			)
		)
		(property "Value" ""
			(at 0 0 180)
			(layer "F.Fab")
			(effects
				(font
					(size 1.27 1.27)
				)
			)
		)
		(duplicate_pad_numbers_are_jumpers no)
		(pad "BH11" smd circle
			(at -25.530048 3.599942 180)
			(size 0.450088 0.450088)
			(layers "F.Cu" "F.Mask" "F.Paste")
			(net "M_L_CPU1_SB_CA<1>")
		)
		(pad "BH12" smd circle
			(at -24.589994 3.599942 180)
			(size 0.450088 0.450088)
			(layers "F.Cu" "F.Mask" "F.Paste")
			(net "GND")
		)
		(pad "BH13" smd circle
			(at -23.64994 3.599942 180)
			(size 0.450088 0.450088)
			(layers "F.Cu" "F.Mask" "F.Paste")
			(net "M_H_CPU1_SB_CA<2>")
		)
		(pad "BH14" smd circle
			(at -22.709886 3.599942 180)
			(size 0.450088 0.450088)
			(layers "F.Cu" "F.Mask" "F.Paste")
			(net "M_H_CPU1_SB_CA<1>")
		)
		(pad "BH15" smd circle
			(at -21.770086 3.599942 180)
			(size 0.450088 0.450088)
			(layers "F.Cu" "F.Mask" "F.Paste")
			(net "GND")
		)
		(pad "BH16" smd circle
			(at -20.830032 3.599942 180)
			(size 0.450088 0.450088)
			(layers "F.Cu" "F.Mask" "F.Paste")
			(net "M_J_CPU1_SB_CA<2>")
		)
		(pad "BH17" smd circle
			(at -19.889978 3.599942 180)
			(size 0.450088 0.450088)
			(layers "F.Cu" "F.Mask" "F.Paste")
			(net "GND")
		)
		(pad "BH18" smd circle
			(at -18.949924 3.599942 180)
			(size 0.450088 0.450088)
			(layers "F.Cu" "F.Mask" "F.Paste")
			(net "M_J_CPU1_SB_CA<1>")
		)
		(pad "BH19" smd circle
			(at -18.010124 3.599942 180)
			(size 0.450088 0.450088)
			(layers "F.Cu" "F.Mask" "F.Paste")
			(net "GND")
		)
		(pad "BH20" smd circle
			(at -17.07007 3.599942 180)
			(size 0.450088 0.450088)
			(layers "F.Cu" "F.Mask" "F.Paste")
			(net "M_I_CPU1_SB_CA<2>")
		)
		(pad "BH21" smd circle
			(at -16.130016 3.599942 180)
			(size 0.450088 0.450088)
			(layers "F.Cu" "F.Mask" "F.Paste")
			(net "M_I_CPU1_SB_CA<1>")
		)
		(pad "BH22" smd circle
			(at -15.189962 3.599942 180)
			(size 0.450088 0.450088)
			(layers "F.Cu" "F.Mask" "F.Paste")
			(net "GND")
		)
		(pad "BH23" smd circle
			(at -14.249908 3.599942 180)
			(size 0.450088 0.450088)
			(layers "F.Cu" "F.Mask" "F.Paste")
			(net "PVDDCR_SOC_P1")
		)
		(pad "BH24" smd circle
			(at -13.310108 3.599942 180)
			(size 0.450088 0.450088)
			(layers "F.Cu" "F.Mask" "F.Paste")
			(net "GND")
		)
		(pad "BH25" smd circle
			(at -12.370054 3.599942 180)
			(size 0.450088 0.450088)
			(layers "F.Cu" "F.Mask" "F.Paste")
			(net "PVDDCR_SOC_P1")
		)
		(pad "BH26" smd circle
			(at -11.43 3.599942 180)
			(size 0.450088 0.450088)
			(layers "F.Cu" "F.Mask" "F.Paste")
			(net "GND")
		)
		(pad "BH27" smd circle
			(at -10.489946 3.599942 180)
			(size 0.450088 0.450088)
			(layers "F.Cu" "F.Mask" "F.Paste")
			(net "PVDD18_S5_P1")
		)
		(pad "BH28" smd circle
			(at -9.549892 3.599942 180)
			(size 0.450088 0.450088)
			(layers "F.Cu" "F.Mask" "F.Paste")
			(net "GND")
		)
		(pad "BH48" smd circle
			(at 9.249918 3.599942 180)
			(size 0.450088 0.450088)
			(layers "F.Cu" "F.Mask" "F.Paste")
			(net "PVDDCR_SOC_P1")
		)
		(pad "BH49" smd circle
			(at 10.189972 3.599942 180)
			(size 0.450088 0.450088)
			(layers "F.Cu" "F.Mask" "F.Paste")
			(net "GND")
		)
		(pad "BH50" smd circle
			(at 11.130026 3.599942 180)
			(size 0.450088 0.450088)
			(layers "F.Cu" "F.Mask" "F.Paste")
			(net "GND")
		)
		(pad "BH51" smd circle
			(at 12.07008 3.599942 180)
			(size 0.450088 0.450088)
			(layers "F.Cu" "F.Mask" "F.Paste")
			(net "PVDDIO_P1")
		)
		(pad "BH52" smd circle
			(at 13.00988 3.599942 180)
			(size 0.450088 0.450088)
			(layers "F.Cu" "F.Mask" "F.Paste")
			(net "GND")
		)
		(pad "BH53" smd circle
			(at 13.949934 3.599942 180)
			(size 0.450088 0.450088)
			(layers "F.Cu" "F.Mask" "F.Paste")
			(net "PVDDIO_P1")
		)
		(pad "BH54" smd circle
			(at 14.889988 3.599942 180)
			(size 0.450088 0.450088)
			(layers "F.Cu" "F.Mask" "F.Paste")
			(net "GND")
		)
		(pad "BH55" smd circle
			(at 15.830042 3.599942 180)
			(size 0.450088 0.450088)
			(layers "F.Cu" "F.Mask" "F.Paste")
			(net "M_C_CPU1_SB_CA<1>")
		)
		(pad "BH56" smd circle
			(at 16.770096 3.599942 180)
			(size 0.450088 0.450088)
			(layers "F.Cu" "F.Mask" "F.Paste")
			(net "M_C_CPU1_SB_CA<2>")
		)
		(pad "BH57" smd circle
			(at 17.709896 3.599942 180)
			(size 0.450088 0.450088)
			(layers "F.Cu" "F.Mask" "F.Paste")
			(net "GND")
		)
		(pad "BH58" smd circle
			(at 18.64995 3.599942 180)
			(size 0.450088 0.450088)
			(layers "F.Cu" "F.Mask" "F.Paste")
			(net "M_D_CPU1_SB_CA<1>")
		)
		(pad "BH59" smd circle
			(at 19.590004 3.599942 180)
			(size 0.450088 0.450088)
			(layers "F.Cu" "F.Mask" "F.Paste")
			(net "GND")
		)
		(pad "BH60" smd circle
			(at 20.530058 3.599942 180)
			(size 0.450088 0.450088)
			(layers "F.Cu" "F.Mask" "F.Paste")
			(net "M_D_CPU1_SB_CA<2>")
		)
		(pad "BH61" smd circle
			(at 21.470112 3.599942 180)
			(size 0.450088 0.450088)
			(layers "F.Cu" "F.Mask" "F.Paste")
			(net "GND")
		)
		(pad "BH62" smd circle
			(at 22.409912 3.599942 180)
			(size 0.450088 0.450088)
			(layers "F.Cu" "F.Mask" "F.Paste")
			(net "M_B_CPU1_SB_CA<1>")
		)
		(pad "BH63" smd circle
			(at 23.349966 3.599942 180)
			(size 0.450088 0.450088)
			(layers "F.Cu" "F.Mask" "F.Paste")
			(net "M_B_CPU1_SB_CA<2>")
		)
		(pad "BH64" smd circle
			(at 24.29002 3.599942 180)
			(size 0.450088 0.450088)
			(layers "F.Cu" "F.Mask" "F.Paste")
			(net "GND")
		)
		(pad "BH65" smd circle
			(at 25.230074 3.599942 180)
			(size 0.450088 0.450088)
			(layers "F.Cu" "F.Mask" "F.Paste")
			(net "M_F_CPU1_SB_CA<1>")
		)
		(pad "BH66" smd circle
			(at 26.170128 3.599942 180)
			(size 0.450088 0.450088)
			(layers "F.Cu" "F.Mask" "F.Paste")
			(net "GND")
		)
		(pad "BH67" smd circle
			(at 27.109928 3.599942 180)
			(size 0.450088 0.450088)
			(layers "F.Cu" "F.Mask" "F.Paste")
			(net "M_F_CPU1_SB_CA<2>")
		)
		(pad "BH68" smd circle
			(at 28.049982 3.599942 180)
			(size 0.450088 0.450088)
			(layers "F.Cu" "F.Mask" "F.Paste")
			(net "GND")
		)
		(pad "BH69" smd circle
			(at 28.990036 3.599942 180)
			(size 0.450088 0.450088)
			(layers "F.Cu" "F.Mask" "F.Paste")
			(net "M_E_CPU1_SB_CA<1>")
		)
		(pad "BH70" smd circle
			(at 29.93009 3.599942 180)
			(size 0.450088 0.450088)
			(layers "F.Cu" "F.Mask" "F.Paste")
			(net "M_E_CPU1_SB_CA<2>")
		)
		(pad "BH71" smd circle
			(at 30.86989 3.599942 180)
			(size 0.450088 0.450088)
			(layers "F.Cu" "F.Mask" "F.Paste")
			(net "GND")
		)
		(pad "BH72" smd circle
			(at 31.809944 3.599942 180)
			(size 0.450088 0.450088)
			(layers "F.Cu" "F.Mask" "F.Paste")
			(net "M_A_CPU1_SB_CA<1>")
		)
		(pad "BH73" smd circle
			(at 32.749998 3.599942 180)
			(size 0.450088 0.450088)
			(layers "F.Cu" "F.Mask" "F.Paste")
			(net "GND")
		)
		(pad "BH74" smd circle
			(at 33.690052 3.599942 180)
			(size 0.450088 0.450088)
			(layers "F.Cu" "F.Mask" "F.Paste")
			(net "M_A_CPU1_SB_CA<2>")
		)
		(pad "BJ1" smd circle
			(at -34.459926 4.409948 180)
			(size 0.450088 0.450088)
			(layers "F.Cu" "F.Mask" "F.Paste")
			(net "GND")
		)
		(pad "BJ2" smd circle
			(at -33.519872 4.409948 180)
			(size 0.450088 0.450088)
			(layers "F.Cu" "F.Mask" "F.Paste")
			(net "M_G_CPU1_SB_CA<3>")
		)
		(pad "BJ3" smd circle
			(at -32.580072 4.409948 180)
			(size 0.450088 0.450088)
			(layers "F.Cu" "F.Mask" "F.Paste")
			(net "M_G_CPU1_SB_CA<4>")
		)
		(pad "BJ4" smd circle
			(at -31.640018 4.409948 180)
			(size 0.450088 0.450088)
			(layers "F.Cu" "F.Mask" "F.Paste")
			(net "PVDDCR_SOC_P1")
		)
		(pad "BJ5" smd circle
			(at -30.699964 4.409948 180)
			(size 0.450088 0.450088)
			(layers "F.Cu" "F.Mask" "F.Paste")
			(net "M_K_CPU1_SB_CA<3>")
		)
		(pad "BJ6" smd circle
			(at -29.75991 4.409948 180)
			(size 0.450088 0.450088)
			(layers "F.Cu" "F.Mask" "F.Paste")
			(net "GND")
		)
		(pad "BJ7" smd circle
			(at -28.82011 4.409948 180)
			(size 0.450088 0.450088)
			(layers "F.Cu" "F.Mask" "F.Paste")
			(net "M_K_CPU1_SB_CA<4>")
		)
		(pad "BJ8" smd circle
			(at -27.880056 4.409948 180)
			(size 0.450088 0.450088)
			(layers "F.Cu" "F.Mask" "F.Paste")
			(net "GND")
		)
		(pad "BJ9" smd circle
			(at -26.940002 4.409948 180)
			(size 0.450088 0.450088)
			(layers "F.Cu" "F.Mask" "F.Paste")
			(net "M_L_CPU1_SB_CA<3>")
		)
		(pad "BJ10" smd circle
			(at -25.999948 4.409948 180)
			(size 0.450088 0.450088)
			(layers "F.Cu" "F.Mask" "F.Paste")
			(net "M_L_CPU1_SB_CA<4>")
		)
		(pad "BJ11" smd circle
			(at -25.059894 4.409948 180)
			(size 0.450088 0.450088)
			(layers "F.Cu" "F.Mask" "F.Paste")
			(net "PVDDCR_SOC_P1")
		)
		(pad "BJ12" smd circle
			(at -24.120094 4.409948 180)
			(size 0.450088 0.450088)
			(layers "F.Cu" "F.Mask" "F.Paste")
			(net "M_H_CPU1_SB_CA<3>")
		)
		(pad "BJ13" smd circle
			(at -23.18004 4.409948 180)
			(size 0.450088 0.450088)
			(layers "F.Cu" "F.Mask" "F.Paste")
			(net "GND")
		)
		(pad "BJ14" smd circle
			(at -22.239986 4.409948 180)
			(size 0.450088 0.450088)
			(layers "F.Cu" "F.Mask" "F.Paste")
			(net "M_H_CPU1_SB_CA<4>")
		)
		(pad "BJ15" smd circle
			(at -21.299932 4.409948 180)
			(size 0.450088 0.450088)
			(layers "F.Cu" "F.Mask" "F.Paste")
			(net "GND")
		)
		(pad "BJ16" smd circle
			(at -20.359878 4.409948 180)
			(size 0.450088 0.450088)
			(layers "F.Cu" "F.Mask" "F.Paste")
			(net "M_J_CPU1_SB_CA<3>")
		)
		(pad "BJ17" smd circle
			(at -19.420078 4.409948 180)
			(size 0.450088 0.450088)
			(layers "F.Cu" "F.Mask" "F.Paste")
			(net "M_J_CPU1_SB_CA<4>")
		)
		(pad "BJ18" smd circle
			(at -18.480024 4.409948 180)
			(size 0.450088 0.450088)
			(layers "F.Cu" "F.Mask" "F.Paste")
			(net "PVDD11_S3_P1")
		)
		(pad "BJ19" smd circle
			(at -17.53997 4.409948 180)
			(size 0.450088 0.450088)
			(layers "F.Cu" "F.Mask" "F.Paste")
			(net "M_I_CPU1_SB_CA<3>")
		)
		(pad "BJ20" smd circle
			(at -16.599916 4.409948 180)
			(size 0.450088 0.450088)
			(layers "F.Cu" "F.Mask" "F.Paste")
			(net "GND")
		)
		(pad "BJ21" smd circle
			(at -15.660116 4.409948 180)
			(size 0.450088 0.450088)
			(layers "F.Cu" "F.Mask" "F.Paste")
			(net "M_I_CPU1_SB_CA<4>")
		)
		(pad "BJ22" smd circle
			(at -14.720062 4.409948 180)
			(size 0.450088 0.450088)
			(layers "F.Cu" "F.Mask" "F.Paste")
			(net "GND")
		)
		(pad "BJ23" smd circle
			(at -13.780008 4.409948 180)
			(size 0.450088 0.450088)
			(layers "F.Cu" "F.Mask" "F.Paste")
			(net "PVDD11_S3_P1")
		)
		(pad "BJ24" smd circle
			(at -12.839954 4.409948 180)
			(size 0.450088 0.450088)
			(layers "F.Cu" "F.Mask" "F.Paste")
			(net "GND")
		)
		(pad "BJ25" smd circle
			(at -11.8999 4.409948 180)
			(size 0.450088 0.450088)
			(layers "F.Cu" "F.Mask" "F.Paste")
			(net "PVDD11_S3_P1")
		)
		(pad "BJ26" smd circle
			(at -10.9601 4.409948 180)
			(size 0.450088 0.450088)
			(layers "F.Cu" "F.Mask" "F.Paste")
			(net "GND")
		)
		(pad "BJ27" smd circle
			(at -10.020046 4.409948 180)
			(size 0.450088 0.450088)
			(layers "F.Cu" "F.Mask" "F.Paste")
			(net "PVDD11_S3_P1")
		)
		(pad "BJ28" smd circle
			(at -9.079992 4.409948 180)
			(size 0.450088 0.450088)
			(layers "F.Cu" "F.Mask" "F.Paste")
			(net "GND")
		)
		(pad "BJ48" smd circle
			(at 8.780018 4.409948 180)
			(size 0.450088 0.450088)
			(layers "F.Cu" "F.Mask" "F.Paste")
			(net "PVDDCR_SOC_P1")
		)
		(pad "BJ49" smd circle
			(at 9.720072 4.409948 180)
			(size 0.450088 0.450088)
			(layers "F.Cu" "F.Mask" "F.Paste")
			(net "GND")
		)
		(pad "BJ50" smd circle
			(at 10.659872 4.409948 180)
			(size 0.450088 0.450088)
			(layers "F.Cu" "F.Mask" "F.Paste")
			(net "PVDDIO_P1")
		)
		(pad "BJ51" smd circle
			(at 11.599926 4.409948 180)
			(size 0.450088 0.450088)
			(layers "F.Cu" "F.Mask" "F.Paste")
			(net "GND")
		)
		(pad "BJ52" smd circle
			(at 12.53998 4.409948 180)
			(size 0.450088 0.450088)
			(layers "F.Cu" "F.Mask" "F.Paste")
			(net "PVDDIO_P1")
		)
		(pad "BJ53" smd circle
			(at 13.480034 4.409948 180)
			(size 0.450088 0.450088)
			(layers "F.Cu" "F.Mask" "F.Paste")
			(net "GND")
		)
		(pad "BJ54" smd circle
			(at 14.420088 4.409948 180)
			(size 0.450088 0.450088)
			(layers "F.Cu" "F.Mask" "F.Paste")
			(net "PVDDIO_P1")
		)
		(pad "BJ55" smd circle
			(at 15.359888 4.409948 180)
			(size 0.450088 0.450088)
			(layers "F.Cu" "F.Mask" "F.Paste")
			(net "M_C_CPU1_SB_CA<4>")
		)
		(pad "BJ56" smd circle
			(at 16.299942 4.409948 180)
			(size 0.450088 0.450088)
			(layers "F.Cu" "F.Mask" "F.Paste")
			(net "GND")
		)
		(pad "BJ57" smd circle
			(at 17.239996 4.409948 180)
			(size 0.450088 0.450088)
			(layers "F.Cu" "F.Mask" "F.Paste")
			(net "M_C_CPU1_SB_CA<3>")
		)
		(pad "BJ58" smd circle
			(at 18.18005 4.409948 180)
			(size 0.450088 0.450088)
			(layers "F.Cu" "F.Mask" "F.Paste")
			(net "PVDDIO_P1")
		)
		(pad "BJ59" smd circle
			(at 19.120104 4.409948 180)
			(size 0.450088 0.450088)
			(layers "F.Cu" "F.Mask" "F.Paste")
			(net "M_D_CPU1_SB_CA<4>")
		)
		(pad "BJ60" smd circle
			(at 20.059904 4.409948 180)
			(size 0.450088 0.450088)
			(layers "F.Cu" "F.Mask" "F.Paste")
			(net "M_D_CPU1_SB_CA<3>")
		)
		(pad "BJ61" smd circle
			(at 20.999958 4.409948 180)
			(size 0.450088 0.450088)
			(layers "F.Cu" "F.Mask" "F.Paste")
			(net "GND")
		)
		(pad "BJ62" smd circle
			(at 21.940012 4.409948 180)
			(size 0.450088 0.450088)
			(layers "F.Cu" "F.Mask" "F.Paste")
			(net "M_B_CPU1_SB_CA<4>")
		)
		(pad "BJ63" smd circle
			(at 22.880066 4.409948 180)
			(size 0.450088 0.450088)
			(layers "F.Cu" "F.Mask" "F.Paste")
			(net "GND")
		)
		(pad "BJ64" smd circle
			(at 23.82012 4.409948 180)
			(size 0.450088 0.450088)
			(layers "F.Cu" "F.Mask" "F.Paste")
			(net "M_B_CPU1_SB_CA<3>")
		)
		(pad "BJ65" smd circle
			(at 24.75992 4.409948 180)
			(size 0.450088 0.450088)
			(layers "F.Cu" "F.Mask" "F.Paste")
			(net "PVDDIO_P1")
		)
		(pad "BJ66" smd circle
			(at 25.699974 4.409948 180)
			(size 0.450088 0.450088)
			(layers "F.Cu" "F.Mask" "F.Paste")
			(net "M_F_CPU1_SB_CA<4>")
		)
		(pad "BJ67" smd circle
			(at 26.640028 4.409948 180)
			(size 0.450088 0.450088)
			(layers "F.Cu" "F.Mask" "F.Paste")
			(net "M_F_CPU1_SB_CA<3>")
		)
		(pad "BJ68" smd circle
			(at 27.580082 4.409948 180)
			(size 0.450088 0.450088)
			(layers "F.Cu" "F.Mask" "F.Paste")
			(net "GND")
		)
		(pad "BJ69" smd circle
			(at 28.519882 4.409948 180)
			(size 0.450088 0.450088)
			(layers "F.Cu" "F.Mask" "F.Paste")
			(net "M_E_CPU1_SB_CA<4>")
		)
		(pad "BJ70" smd circle
			(at 29.459936 4.409948 180)
			(size 0.450088 0.450088)
			(layers "F.Cu" "F.Mask" "F.Paste")
			(net "GND")
		)
		(pad "BJ71" smd circle
			(at 30.39999 4.409948 180)
			(size 0.450088 0.450088)
			(layers "F.Cu" "F.Mask" "F.Paste")
			(net "M_E_CPU1_SB_CA<3>")
		)
		(pad "BJ72" smd circle
			(at 31.340044 4.409948 180)
			(size 0.450088 0.450088)
			(layers "F.Cu" "F.Mask" "F.Paste")
			(net "PVDDIO_P1")
		)
		(pad "BJ73" smd circle
			(at 32.280098 4.409948 180)
			(size 0.450088 0.450088)
			(layers "F.Cu" "F.Mask" "F.Paste")
			(net "M_A_CPU1_SB_CA<4>")
		)
		(pad "BJ74" smd circle
			(at 33.219898 4.409948 180)
			(size 0.450088 0.450088)
			(layers "F.Cu" "F.Mask" "F.Paste")
			(net "M_A_CPU1_SB_CA<3>")
		)
		(pad "BJ75" smd circle
			(at 34.159952 4.409948 180)
			(size 0.450088 0.450088)
			(layers "F.Cu" "F.Mask" "F.Paste")
			(net "GND")
		)
		(pad "BK2" smd circle
			(at -33.990026 5.219954 180)
			(size 0.450088 0.450088)
			(layers "F.Cu" "F.Mask" "F.Paste")
			(net "M_G_CPU1_SB_CA<6>")
		)
		(pad "BK3" smd circle
			(at -33.049972 5.219954 180)
			(size 0.450088 0.450088)
			(layers "F.Cu" "F.Mask" "F.Paste")
			(net "GND")
		)
		(pad "BK4" smd circle
			(at -32.109918 5.219954 180)
			(size 0.450088 0.450088)
			(layers "F.Cu" "F.Mask" "F.Paste")
			(net "M_G_CPU1_SB_CA<5>")
		)
		(pad "BK5" smd circle
			(at -31.170118 5.219954 180)
			(size 0.450088 0.450088)
			(layers "F.Cu" "F.Mask" "F.Paste")
			(net "GND")
		)
		(pad "BK6" smd circle
			(at -30.230064 5.219954 180)
			(size 0.450088 0.450088)
			(layers "F.Cu" "F.Mask" "F.Paste")
			(net "M_K_CPU1_SB_CA<6>")
		)
		(pad "BK7" smd circle
			(at -29.29001 5.219954 180)
			(size 0.450088 0.450088)
			(layers "F.Cu" "F.Mask" "F.Paste")
			(net "M_K_CPU1_SB_CA<5>")
		)
		(pad "BK8" smd circle
			(at -28.349956 5.219954 180)
			(size 0.450088 0.450088)
			(layers "F.Cu" "F.Mask" "F.Paste")
			(net "GND")
		)
		(pad "BK9" smd circle
			(at -27.409902 5.219954 180)
			(size 0.450088 0.450088)
			(layers "F.Cu" "F.Mask" "F.Paste")
			(net "M_L_CPU1_SB_CA<6>")
		)
		(pad "BK10" smd circle
			(at -26.470102 5.219954 180)
			(size 0.450088 0.450088)
			(layers "F.Cu" "F.Mask" "F.Paste")
			(net "GND")
		)
		(pad "BK11" smd circle
			(at -25.530048 5.219954 180)
			(size 0.450088 0.450088)
			(layers "F.Cu" "F.Mask" "F.Paste")
			(net "M_L_CPU1_SB_CA<5>")
		)
		(pad "BK12" smd circle
			(at -24.589994 5.219954 180)
			(size 0.450088 0.450088)
			(layers "F.Cu" "F.Mask" "F.Paste")
			(net "GND")
		)
	)
)
